# BASEBOARD_FAB2 (Tioga Pass) — schematic netlist excerpt (pin names and nets, part order shuffled) for the footprints in the layout excerpt that follows; sources: Cadence DE-HDL packaged netlist, KiCad conversion of Wiwynn_Tioga_Pass_MB.brd

C1M31  CAP_A  0.01UF 25V 10% X7R  pkg 0402V  page 113 : A = P3V3_STBY ; B = GND
C4P3  CAP  100UF 4V 20% X5R  pkg 0805  page 42 : A = PVCCMCP_CPU0 ; B = GND
C8M11  CAP  100UF 4V 20% X5R  pkg 0805  page 228 : A = PVDDQ_KLM ; B = GND

(kicad_pcb
	(version 20260206)
	(generator "pcbnew")
	(generator_version "10.0")
	(general
		(thickness 1.6)
		(legacy_teardrops no)
	)
	(paper "A4")
	(title_block
		(title "Wiwynn_Tioga_Pass_MB.brd")
		(comment 1 "Tioga Pass / footprints 3926-3928 of 4770")
	)
	(layers
		(0 "F.Cu" signal "TOP")
		(4 "In1.Cu" signal "L2GND")
		(6 "In2.Cu" signal "L3")
		(8 "In3.Cu" signal "L4GND")
		(10 "In4.Cu" signal "L5")
		(12 "In5.Cu" signal "L6GND")
		(14 "In6.Cu" signal "L7VCC")
		(16 "In7.Cu" signal "L8VCC")
		(18 "In8.Cu" signal "L9GND")
		(20 "In9.Cu" signal "L10")
		(22 "In10.Cu" signal "L11GND")
		(24 "In11.Cu" signal "L12")
		(26 "In12.Cu" signal "L13GND")
		(2 "B.Cu" signal "BOTTOM")
		(9 "F.Adhes" user "F.Adhesive")
		(11 "B.Adhes" user "B.Adhesive")
		(13 "F.Paste" user "Package Geometry/Pastemask Top")
		(15 "B.Paste" user "Package Geometry/Pastemask Bottom")
		(5 "F.SilkS" user "Ref Des/Silkscreen Top")
		(7 "B.SilkS" user "Ref Des/Silkscreen Bottom")
		(1 "F.Mask" user "Board Geometry/Soldermask Top")
		(3 "B.Mask" user "Board Geometry/Soldermask Bottom")
		(17 "Dwgs.User" user "User.Drawings")
		(19 "Cmts.User" user "User.Comments")
		(21 "Eco1.User" user "User.Eco1")
		(23 "Eco2.User" user "User.Eco2")
		(25 "Edge.Cuts" user "Board Geometry/Outline")
		(27 "Margin" user)
		(31 "F.CrtYd" user "Package Geometry/Place Bound Top")
		(29 "B.CrtYd" user "Package Geometry/Place Bound Bottom")
		(35 "F.Fab" user "Ref Des/Assembly Top")
		(33 "B.Fab" user "Ref Des/Assembly Bottom")
	)
	(footprint ""
		(layer "B.Cu")
		(at 496.34648 -130.52552)
		(property "Reference" "C1M31"
			(at 0 0 0)
			(layer "B.SilkS")
			(hide yes)
			(effects
				(font
					(size 1.27 1.27)
				)
				(justify mirror)
			)
		)
		(property "Value" ""
			(at 0 0 0)
			(layer "B.Fab")
			(effects
				(font
					(size 1.27 1.27)
				)
				(justify mirror)
			)
		)
		(duplicate_pad_numbers_are_jumpers no)
		(fp_poly
			(pts
				(xy -0.3048 -0.1016) (xy -0.3048 0.9906) (xy 0.3048 0.9906) (xy 0.3048 -0.1016)
			)
			(stroke
				(width 0)
				(type default)
			)
			(fill no)
			(layer "B.CrtYd")
		)
		(fp_line
			(start -0.3048 -0.1016)
			(end 0.3048 -0.1016)
			(stroke
				(width 0.1)
				(type default)
			)
			(layer "B.Fab")
		)
		(fp_line
			(start -0.3048 0.9906)
			(end -0.3048 -0.1016)
			(stroke
				(width 0.1)
				(type default)
			)
			(layer "B.Fab")
		)
		(fp_line
			(start 0.3048 -0.1016)
			(end 0.3048 0.9906)
			(stroke
				(width 0.1)
				(type default)
			)
			(layer "B.Fab")
		)
		(fp_line
			(start 0.3048 0.9906)
			(end -0.3048 0.9906)
			(stroke
				(width 0.1)
				(type default)
			)
			(layer "B.Fab")
		)
		(pad "1" smd rect
			(at 0 0 180)
			(size 0.508 0.508)
			(layers "B.Cu" "B.Mask" "B.Paste")
			(net "P3V3_STBY")
		)
		(pad "2" smd rect
			(at 0 0.889 180)
			(size 0.508 0.508)
			(layers "B.Cu" "B.Mask" "B.Paste")
			(net "GND")
		)
		(zone
			(layer "B.Cu")
			(hatch none 0.5)
			(connect_pads
				(clearance 0)
			)
			(min_thickness 0.25)
			(keepout
				(tracks allowed)
				(vias not_allowed)
				(pads allowed)
				(copperpour not_allowed)
				(footprints allowed)
			)
			(placement
				(enabled no)
				(sheetname "")
			)
			(fill
				(thermal_gap 0.5)
				(thermal_bridge_width 0.5)
				(island_removal_mode 0)
			)
			(polygon
				(pts
					(xy 496.60048 -130.27152) (xy 496.09248 -130.27152) (xy 496.09248 -129.89052) (xy 496.60048 -129.89052)
				)
			)
		)
		(zone
			(layer "B.Cu")
			(hatch none 0.5)
			(connect_pads
				(clearance 0)
			)
			(min_thickness 0.25)
			(keepout
				(tracks not_allowed)
				(vias allowed)
				(pads allowed)
				(copperpour not_allowed)
				(footprints allowed)
			)
			(placement
				(enabled no)
				(sheetname "")
			)
			(fill
				(thermal_gap 0.5)
				(thermal_bridge_width 0.5)
				(island_removal_mode 0)
			)
			(polygon
				(pts
					(xy 496.60048 -129.89052) (xy 496.09248 -129.89052) (xy 496.09248 -130.27152) (xy 496.60048 -130.27152)
				)
			)
		)
	)
	(footprint ""
		(layer "B.Cu")
		(at 112.0775 -126.08306 90)
		(property "Reference" "C8M11"
			(at 0 0 90)
			(layer "B.SilkS")
			(hide yes)
			(effects
				(font
					(size 1.27 1.27)
				)
				(justify mirror)
			)
		)
		(property "Value" ""
			(at 0 0 90)
			(layer "B.Fab")
			(effects
				(font
					(size 1.27 1.27)
				)
				(justify mirror)
			)
		)
		(duplicate_pad_numbers_are_jumpers no)
		(fp_poly
			(pts
				(xy 0.7239 -0.2159) (xy -0.7239 -0.2159) (xy -0.7239 1.9939) (xy 0.7239 1.9939)
			)
			(stroke
				(width 0)
				(type default)
			)
			(fill no)
			(layer "B.CrtYd")
		)
		(fp_line
			(start 0.7239 -0.2159)
			(end 0.7239 1.9939)
			(stroke
				(width 0.1)
				(type default)
			)
			(layer "B.Fab")
		)
		(fp_line
			(start -0.7239 -0.2159)
			(end 0.7239 -0.2159)
			(stroke
				(width 0.1)
				(type default)
			)
			(layer "B.Fab")
		)
		(fp_line
			(start 0.7239 1.9939)
			(end -0.7239 1.9939)
			(stroke
				(width 0.1)
				(type default)
			)
			(layer "B.Fab")
		)
		(fp_line
			(start -0.7239 1.9939)
			(end -0.7239 -0.2159)
			(stroke
				(width 0.1)
				(type default)
			)
			(layer "B.Fab")
		)
		(pad "1" smd rect
			(at 0 0 270)
			(size 1.27 1.016)
			(layers "B.Cu" "B.Mask" "B.Paste")
			(net "PVDDQ_KLM")
		)
		(pad "2" smd rect
			(at 0 1.778 270)
			(size 1.27 1.016)
			(layers "B.Cu" "B.Mask" "B.Paste")
			(net "GND")
		)
		(zone
			(layer "B.Cu")
			(hatch none 0.5)
			(connect_pads
				(clearance 0)
			)
			(min_thickness 0.25)
			(keepout
				(tracks not_allowed)
				(vias allowed)
				(pads allowed)
				(copperpour not_allowed)
				(footprints allowed)
			)
			(placement
				(enabled no)
				(sheetname "")
			)
			(fill
				(thermal_gap 0.5)
				(thermal_bridge_width 0.5)
				(island_removal_mode 0)
			)
			(polygon
				(pts
					(xy 112.5855 -126.71806) (xy 112.5855 -125.44806) (xy 113.3475 -125.44806) (xy 113.3475 -126.71806)
				)
			)
		)
	)
	(footprint ""
		(layer "B.Cu")
		(at 277.217886 -79.60614 180)
		(property "Reference" "C4P3"
			(at 0 0 0)
			(layer "B.SilkS")
			(hide yes)
			(effects
				(font
					(size 1.27 1.27)
				)
				(justify mirror)
			)
		)
		(property "Value" ""
			(at 0 0 0)
			(layer "B.Fab")
			(effects
				(font
					(size 1.27 1.27)
				)
				(justify mirror)
			)
		)
		(duplicate_pad_numbers_are_jumpers no)
		(fp_poly
			(pts
				(xy 0.7239 -0.2159) (xy -0.7239 -0.2159) (xy -0.7239 1.9939) (xy 0.7239 1.9939)
			)
			(stroke
				(width 0)
				(type default)
			)
			(fill no)
			(layer "B.CrtYd")
		)
		(fp_line
			(start 0.7239 1.9939)
			(end -0.7239 1.9939)
			(stroke
				(width 0.1)
				(type default)
			)
			(layer "B.Fab")
		)
		(fp_line
			(start 0.7239 -0.2159)
			(end 0.7239 1.9939)
			(stroke
				(width 0.1)
				(type default)
			)
			(layer "B.Fab")
		)
		(fp_line
			(start -0.7239 1.9939)
			(end -0.7239 -0.2159)
			(stroke
				(width 0.1)
				(type default)
			)
			(layer "B.Fab")
		)
		(fp_line
			(start -0.7239 -0.2159)
			(end 0.7239 -0.2159)
			(stroke
				(width 0.1)
				(type default)
			)
			(layer "B.Fab")
		)
		(pad "1" smd rect
			(at 0 0)
			(size 1.27 1.016)
			(layers "B.Cu" "B.Mask" "B.Paste")
			(net "PVCCMCP_CPU0")
		)
		(pad "2" smd rect
			(at 0 1.778)
			(size 1.27 1.016)
			(layers "B.Cu" "B.Mask" "B.Paste")
			(net "GND")
		)
		(zone
			(layer "B.Cu")
			(hatch none 0.5)
			(connect_pads
				(clearance 0)
			)
			(min_thickness 0.25)
			(keepout
				(tracks not_allowed)
				(vias allowed)
				(pads allowed)
				(copperpour not_allowed)
				(footprints allowed)
			)
			(placement
				(enabled no)
				(sheetname "")
			)
			(fill
				(thermal_gap 0.5)
				(thermal_bridge_width 0.5)
				(island_removal_mode 0)
			)
			(polygon
				(pts
					(xy 276.582886 -80.11414) (xy 277.852886 -80.11414) (xy 277.852886 -80.87614) (xy 276.582886 -80.87614)
				)
			)
		)
	)
)
